FILE_TYPE = CONNECTIVITY;
{Allegro Design Entry HDL 16.6-p007 (v16-6-112F) 10/10/2012}
"PAGE_NUMBER" = 224;
0"NC";
1"PVDDQ_GHJ\g";
2"GND\g";
3"GND\g";
4"GND\g";
5"GND\g";
6"GND\g";
7"GND\g";
8"GND\g";
9"GND\g";
10"GND\g";
11"GND\g";
12"PVDDQ_GHJ\g";
13"GND\g";
14"GND\g";
15"GND\g";
16"VR_FET_SW_P12V_STBY_PVDDQ_GHJ\g";
17"GND\g";
18"P5V_STBY\g";
19"P5V_STBY\g";
20"VR_FET_SW_P12V_STBY_PVDDQ_GHJ\g";
21"VR_PVDDQ_GHJ_PH2_SW";
22"VR_PVDDQ_GHJ_AIREF2";
23"VR_PVDDQ_GHJ_PH2_VCIN";
24"VR_PVDDQ_GHJ_PH2_PHASE";
25"VR_PVDDQ_GHJ_PH1_PHASE";
26"VR_PVDDQ_GHJ_PH1_BOOT_R";
27"A_TSENSE_PVDDQ_GHJ";
28"NC_PVDDQ_GHJ_PH2_P31";
29"VR_PVDDQ_GHJ_PH1_SW";
30"TP_PVDDQ_GHJ_PH2_GL_0";
31"VR_PVDDQ_GHJ_PH1_BOOT";
32"VR_PVDDQ_GHJ_PWM2";
33"VR_PVDDQ_GHJ_PH2_BOOT";
34"VR_PVDDQ_GHJ_PH2_BOOT_R";
35"VR_PVDDQ_GHJ_PH1_VCIN";
36"A_TSENSE_PVDDQ_GHJ";
37"NC_PVDDQ_GHJ_PH1_P31";
38"VR_PVDDQ_GHJ_AIREF1";
39"UN$224$3D01R5F-GP$I119$2";
40"VR_PVDDQ_GHJ_PWM1";
41"TP_PVDDQ_GHJ_PH1_GL_1";
42"TP_PVDDQ_GHJ_PH2_GL_1";
43"ISENSE_PVDDQ_GHJ_PH1_IMON";
44"VR_PVDDQ_GHJ_PH1_OCSET"VOLTAGE"3.6";
45"TP_PVDDQ_GHJ_PH1_GL_0";
46"ISENSE_PVDDQ_GHJ_PH2_IMON";
47"VR_PVDDQ_GHJ_PH2_OCSET"VOLTAGE"3.6";
48"UN$224$3D01R5F-GP$I129$2";
%"PVDDQ_GHJ"
"1","(4000,2050)","0","mstr_symbols","I1";
;
CDS_LIB"mstr_symbols"
HDL_POWER"PVDDQ_GHJ"
BODY_TYPE"PLUMBING"
VOLTAGE"1.2V";
"G\NAC"1;
%"IR354XX"
"1","(1475,2250)","0","mstr_discrete","I110";
;
CDS_SEC"1"
PACK_TYPE"SM"
SEC_TYPE"SM"
SEC"1"
CDS_LOCATION"EU1G1"
CDS_LIB"mstr_discrete"
NO_XNET_CONNECTION"1"
LOCATION"EU1G1"
VALUE"IR35411"
MATERIAL"IC"
PART_NUMBER"H73688-001";
"TOUT_FLT"
$PN"36"36;
"NC"
$PN"31"37;
"OCSET"
$PN"37"44;
"IOUT"
$PN"38"43;
"SW"
$PN"10"29;
"BOOST"
$PN"33"26;
"REFIN"
$PN"39"38;
"PWM"
$PN"34"40;
"PHASE"
$PN"32"25;
"VIN<0>"
$PN"25"20;
"VCC"
$PN"3"35;
"VIN<1>"
$PN"30"20;
"EN"
$PN"35"18;
"VDRV"
$PN"4"18;
"VOS"
$PN"1"1;
"LGND"
$PN"2"10;
"PGND<1>"
$PN"7"10;
"PGND<2>"
$PN"40"10;
"PGND<0>"
$PN"5"10;
"GL<0>"
$PN"6"45;
"GL<1>"
$PN"41"41;
%"IR354XX"
"1","(1500,-125)","0","mstr_discrete","I111";
;
CDS_SEC"1"
PACK_TYPE"SM"
SEC_TYPE"SM"
SEC"1"
CDS_LOCATION"EU1F1"
CDS_LIB"mstr_discrete"
PART_NUMBER"H73688-001"
VALUE"IR35411"
LOCATION"EU1F1"
MATERIAL"IC";
"TOUT_FLT"
$PN"36"27;
"NC"
$PN"31"28;
"OCSET"
$PN"37"47;
"IOUT"
$PN"38"46;
"SW"
$PN"10"21;
"BOOST"
$PN"33"34;
"REFIN"
$PN"39"22;
"PWM"
$PN"34"32;
"PHASE"
$PN"32"24;
"VIN<0>"
$PN"25"16;
"VCC"
$PN"3"23;
"VIN<1>"
$PN"30"16;
"EN"
$PN"35"19;
"VDRV"
$PN"4"19;
"VOS"
$PN"1"12;
"LGND"
$PN"2"15;
"PGND<1>"
$PN"7"15;
"PGND<2>"
$PN"40"15;
"PGND<0>"
$PN"5"15;
"GL<0>"
$PN"6"30;
"GL<1>"
$PN"41"42;
%"RES"
"2","(4275,2400)","0","mstr_discrete","I112";
;
CDS_LOCATION"R1G26"
CDS_SEC"1"
$SEC"1"
CDS_LIB"mstr_discrete"
MATERIAL"EMPTY"
LOCATION"R1G26"
PART_NUMBER"G21796-187"
VALUE"68.1K"
TOLERANCE"1%"
PACK_TYPE"0402"
WATTAGE"1/16W";
"A"
$PN"1"44;
"B"
$PN"2"2;
%"GND"
"1","(4275,2100)","0","mstr_symbols","I113";
;
HDL_POWER"GND"
VOLTAGE"0"
CDS_LIB"mstr_symbols"
SIZE"1B"
BODY_TYPE"PLUMBING"
BOM_COST"PROC_VRD_VCCIN_CPU0"
ROOM"PVCCIN_CPU0_PWR_VR";
"A\NAC"2;
%"RES"
"2","(4300,25)","0","mstr_discrete","I114";
;
CDS_LOCATION"R1G25"
CDS_SEC"1"
$SEC"1"
CDS_LIB"mstr_discrete"
LOCATION"R1G25"
VALUE"68.1K"
TOLERANCE"1%"
WATTAGE"1/16W"
PART_NUMBER"G21796-187"
MATERIAL"EMPTY"
PACK_TYPE"0402";
"A"
$PN"1"47;
"B"
$PN"2"3;
%"GND"
"1","(4300,-275)","0","mstr_symbols","I115";
;
SIZE"1B"
HDL_POWER"GND"
VOLTAGE"0"
CDS_LIB"mstr_symbols"
BODY_TYPE"PLUMBING"
BOM_COST"PROC_VRD_VCCIN_CPU0"
ROOM"PVCCIN_CPU0_PWR_VR";
"A\NAC"3;
%"CAP_A"
"1","(700,1725)","0","dev_discrete","I117";
;
CDS_SEC"1"
$SEC"1"
CDS_LOCATION"CT30"
CDS_LIB"dev_discrete"
ROOM"PVCCIN_CPU0_PWR_VR"
TOLERANCE"10%"
MATERIAL"X7R"
PART_NUMBER"A36096-030"
PACK_TYPE"0402V"
VALUE"0.1UF"
VOLTAGE"16V"
STATUS"NOPOP"
LOCATION"CT30";
"B"
$PN"2"4;
"A"
$PN"1"38;
%"GND"
"1","(700,1475)","0","mstr_symbols","I118";
;
CDS_LIB"mstr_symbols"
BODY_TYPE"PLUMBING"
ROOM"PVCCIN_CPU0_PWR_VR"
BOM_COST"PROC_VRD_VCCIN_CPU0"
SIZE"1B"
VOLTAGE"0"
HDL_POWER"GND";
"A\NAC"4;
%"3D01R5F-GP"
"1","(2700,1500)","4","w_hdl","I119";
;
CDS_SEC"1"
$SEC"1"
CDS_LOCATION"RT20"
PACK_TYPE"SMD-RG5"
PART_NUMBER"64.3R015.16L"
CDS_LIB"w_hdl"
CDS_LMAN_SYM_OUTLINE"-50,75,50,-75"
VALUE"3D01R5F-GP"
LOCATION"RT20"
STATUS"NOPOP";
"2"
$PN"2"39;
"1"
$PN"1"5;
%"GND"
"1","(2700,1275)","0","mstr_symbols","I120";
;
CDS_LIB"mstr_symbols"
ROOM"PVCCIN_CPU0_PWR_VR"
BOM_COST"PROC_VRD_VCCIN_CPU0"
BODY_TYPE"PLUMBING"
VOLTAGE"0"
SIZE"1B"
HDL_POWER"GND";
"A\NAC"5;
%"SC2K2P50V3KX-GP"
"1","(2700,1800)","0","w_hdl","I121";
;
CDS_SEC"1"
$SEC"1"
CDS_LOCATION"CT29"
CDS_LMAN_SYM_OUTLINE"-50,25,50,-25"
CDS_LIB"w_hdl"
PART_NUMBER"78.22224.2BL"
PACK_TYPE"SMD-BCG6"
LOCATION"CT29"
STATUS"NOPOP"
VALUE"SC2K2P50V3KX-GP";
"2"
$PN"2"39;
"1"
$PN"1"29;
%"CAP"
"1","(2600,2225)","0","mstr_discrete","I122";
;
CDS_SEC"1"
$SEC"1"
CDS_LOCATION"CT28"
CDS_LIB"mstr_discrete"
ROOM"VDDQ_KLM_PWR_VR"
PACK_TYPE"0402LF"
MATERIAL"X7R"
STATUS"NOPOP"
PART_NUMBER"A36096-046"
TOLERANCE"10%"
VALUE"1000PF"
VOLTAGE"50V"
LOCATION"CT28";
"A"
$PN"1"36;
"B"
$PN"2"6;
%"GND"
"1","(2600,2025)","0","mstr_symbols","I123";
;
CDS_LIB"mstr_symbols"
ROOM"VDDQ_KLM_PWR_VR"
VOLTAGE"0"
BODY_TYPE"PLUMBING"
SIZE"1B"
HDL_POWER"GND";
"A\NAC"6;
%"CAP_A"
"1","(800,-625)","0","dev_discrete","I124";
;
CDS_SEC"1"
$SEC"1"
CDS_LOCATION"CT31"
CDS_LIB"dev_discrete"
ROOM"PVCCIN_CPU0_PWR_VR"
VALUE"0.1UF"
VOLTAGE"16V"
TOLERANCE"10%"
MATERIAL"X7R"
PART_NUMBER"A36096-030"
LOCATION"CT31"
PACK_TYPE"0402V"
STATUS"NOPOP";
"B"
$PN"2"7;
"A"
$PN"1"22;
%"GND"
"1","(800,-875)","0","mstr_symbols","I125";
;
BODY_TYPE"PLUMBING"
ROOM"PVCCIN_CPU0_PWR_VR"
BOM_COST"PROC_VRD_VCCIN_CPU0"
SIZE"1B"
VOLTAGE"0"
HDL_POWER"GND"
CDS_LIB"mstr_symbols";
"A\NAC"7;
%"SC2K2P50V3KX-GP"
"1","(2800,-575)","0","w_hdl","I127";
;
CDS_SEC"1"
$SEC"1"
CDS_LOCATION"CT33"
CDS_LIB"w_hdl"
CDS_LMAN_SYM_OUTLINE"-50,25,50,-25"
PART_NUMBER"78.22224.2BL"
PACK_TYPE"SMD-BCG6"
VALUE"SC2K2P50V3KX-GP"
STATUS"NOPOP"
LOCATION"CT33";
"2"
$PN"2"48;
"1"
$PN"1"21;
%"GND"
"1","(2800,-1100)","0","mstr_symbols","I128";
;
HDL_POWER"GND"
SIZE"1B"
VOLTAGE"0"
BODY_TYPE"PLUMBING"
BOM_COST"PROC_VRD_VCCIN_CPU0"
ROOM"PVCCIN_CPU0_PWR_VR"
CDS_LIB"mstr_symbols";
"A\NAC"8;
%"3D01R5F-GP"
"1","(2800,-875)","4","w_hdl","I129";
;
CDS_SEC"1"
$SEC"1"
CDS_LOCATION"RT22"
CDS_LMAN_SYM_OUTLINE"-50,75,50,-75"
CDS_LIB"w_hdl"
PART_NUMBER"64.3R015.16L"
PACK_TYPE"SMD-RG5"
LOCATION"RT22"
STATUS"NOPOP"
VALUE"3D01R5F-GP";
"2"
$PN"2"48;
"1"
$PN"1"8;
%"CAP"
"1","(2700,-75)","0","mstr_discrete","I130";
;
CDS_SEC"1"
$SEC"1"
CDS_LOCATION"CT32"
CDS_LIB"mstr_discrete"
ROOM"VDDQ_KLM_PWR_VR"
PACK_TYPE"0402LF"
PART_NUMBER"A36096-046"
VOLTAGE"50V"
STATUS"NOPOP"
LOCATION"CT32"
TOLERANCE"10%"
MATERIAL"X7R"
VALUE"1000PF";
"A"
$PN"1"27;
"B"
$PN"2"9;
%"GND"
"1","(2700,-300)","0","mstr_symbols","I131";
;
CDS_LIB"mstr_symbols"
ROOM"VDDQ_KLM_PWR_VR"
VOLTAGE"0"
BODY_TYPE"PLUMBING"
SIZE"1B"
HDL_POWER"GND";
"A\NAC"9;
%"RES"
"1","(-275,2000)","0","mstr_discrete","I132";
;
CDS_SEC"1"
$SEC"1"
CDS_LOCATION"RT19"
CDS_LIB"mstr_discrete"
BOM_COST"DEBUG"
ROOM"BMC_DEBUG_HEADER"
LOCATION"RT19"
WATTAGE"1/16W"
PACK_TYPE"0402"
MATERIAL"CHIP"
TOLERANCE"5%"
VALUE"0.0"
PART_NUMBER"G21497-005";
"B"
$PN"2"26;
"A"
$PN"1"31;
%"RES"
"1","(50,-325)","0","mstr_discrete","I133";
;
CDS_SEC"1"
$SEC"1"
CDS_LOCATION"RT21"
CDS_LIB"mstr_discrete"
BOM_COST"DEBUG"
ROOM"BMC_DEBUG_HEADER"
LOCATION"RT21"
VALUE"0.0"
PART_NUMBER"G21497-005"
WATTAGE"1/16W"
PACK_TYPE"0402"
TOLERANCE"5%"
MATERIAL"CHIP";
"B"
$PN"2"34;
"A"
$PN"1"33;
%"GND"
"1","(2325,1500)","0","mstr_symbols","I19";
;
HDL_POWER"GND"
CDS_LIB"mstr_symbols"
VOLTAGE"0"
BODY_TYPE"PLUMBING"
SIZE"1B"
BOM_COST"VDDQ_GHJ_PWR_VR"
ROOM"VDDQ_GHJ_PWR_VR";
"A\NAC"10;
%"GND"
"1","(-2700,2075)","0","mstr_symbols","I35";
;
HDL_POWER"GND"
CDS_LIB"mstr_symbols"
VOLTAGE"0"
BOM_COST"VDDQ_GHJ_PWR_VR"
ROOM"VDDQ_GHJ_PWR_VR"
SIZE"1B"
BODY_TYPE"PLUMBING";
"A\NAC"11;
%"CAP"
"1","(-1125,1900)","2","mstr_discrete","I44";
;
CDS_SEC"1"
ROOM"VDDQ_GHJ_PWR_VR"
CDS_LOCATION"C1G11"
SEC"1"
SEC_TYPE"0402"
SPOF"TRUE"
CDS_LIB"mstr_discrete"
MATERIAL"X7R"
PACK_TYPE"0402"
VALUE"0.220UF"
PART_NUMBER"A36096-104"
LOCATION"C1G11"
VOLTAGE"16V"
TOLERANCE"10%";
"A"
$PN"1"31;
"B"
$PN"2"25;
%"CAP"
"1","(-2700,2525)","0","mstr_discrete","I45";
;
CDS_SEC"1"
SEC_TYPE"0805"
SEC"1"
CDS_LOCATION"C9U6"
ROOM"VDDQ_GHJ_PWR_VR"
CDS_LIB"mstr_discrete"
LOCATION"C9U6"
PART_NUMBER"C95333-007"
VALUE"10UF"
PACK_TYPE"0805"
TOLERANCE"10%"
VOLTAGE"16V"
MATERIAL"X6S";
"A"
$PN"1"20;
"B"
$PN"2"11;
%"CAP"
"1","(-2450,2550)","0","mstr_discrete","I46";
;
CDS_SEC"1"
SEC_TYPE"0805"
SEC"1"
CDS_LOCATION"C9U4"
ROOM"VDDQ_GHJ_PWR_VR"
CDS_LIB"mstr_discrete"
VALUE"10UF"
LOCATION"C9U4"
VOLTAGE"16V"
PART_NUMBER"C95333-007"
PACK_TYPE"0805"
MATERIAL"X6S"
TOLERANCE"10%";
"A"
$PN"1"20;
"B"
$PN"2"11;
%"CAP"
"1","(-2175,2550)","0","mstr_discrete","I47";
;
CDS_SEC"1"
SEC_TYPE"0805"
ROOM"VDDQ_GHJ_PWR_VR"
CDS_LOCATION"C9T4"
SEC"1"
CDS_LIB"mstr_discrete"
PACK_TYPE"0805"
LOCATION"C9T4"
PART_NUMBER"C95333-007"
VALUE"10UF"
TOLERANCE"10%"
VOLTAGE"16V"
MATERIAL"X6S";
"A"
$PN"1"20;
"B"
$PN"2"11;
%"CAP"
"1","(-1925,2450)","0","mstr_discrete","I48";
;
CDS_SEC"1"
CDS_LOCATION"C1F27"
ROOM"VDDQ_GHJ_PWR_VR"
SEC"1"
SEC_TYPE"0402"
CDS_LIB"mstr_discrete"
LOCATION"C1F27"
PART_NUMBER"D97712-011"
VALUE"1.0UF"
TOLERANCE"10%"
PACK_TYPE"0402"
VOLTAGE"16V"
MATERIAL"X6S";
"A"
$PN"1"20;
"B"
$PN"2"11;
%"CAP"
"1","(-1375,2550)","0","mstr_discrete","I50";
;
CDS_SEC"1"
SEC_TYPE"0402"
ROOM"VDDQ_GHJ_PWR_VR"
SEC"1"
CDS_LOCATION"C1G6"
CDS_LIB"mstr_discrete"
LOCATION"C1G6"
VALUE"1.0UF"
VOLTAGE"16V"
MATERIAL"X6S"
PACK_TYPE"0402"
TOLERANCE"10%"
PART_NUMBER"D97712-011";
"A"
$PN"1"35;
"B"
$PN"2"11;
%"CAP_A"
"1","(-1675,2500)","0","dev_discrete","I51";
;
SEC"1"
SEC_TYPE"0402V"
CDS_SEC"1"
CDS_LOCATION"C1G14"
ROOM"VDDQ_GHJ_PWR_VR"
CDS_LIB"dev_discrete"
LOCATION"C1G14"
PART_NUMBER"A36096-030"
VALUE"0.1UF"
PACK_TYPE"0402V"
MATERIAL"X7R"
VOLTAGE"16V"
TOLERANCE"10%";
"B"
$PN"2"11;
"A"
$PN"1"20;
%"RES"
"1","(-1125,3050)","0","mstr_discrete","I52";
;
CDS_SEC"1"
SEC_TYPE"0402"
SEC"1"
CDS_LOCATION"R9U1"
ROOM"VDDQ_GHJ_PWR_VR"
CDS_LIB"mstr_discrete"
PART_NUMBER"G21796-090"
PACK_TYPE"0402"
WATTAGE"1/16W"
MATERIAL"CHIP"
LOCATION"R9U1"
TOLERANCE"1%"
VALUE"1.0";
"B"
$PN"2"18;
"A"
$PN"1"35;
%"CAP_A"
"1","(-525,2500)","2","dev_discrete","I53";
;
CDS_LOCATION"C1G4"
CDS_SEC"1"
SEC_TYPE"0402V"
SEC"1"
ROOM"VDDQ_GHJ_PWR_VR"
CDS_LIB"dev_discrete"
PACK_TYPE"0402V"
PART_NUMBER"D97712-004"
LOCATION"C1G4"
VALUE"1.0UF"
MATERIAL"X6S"
TOLERANCE"10%"
VOLTAGE"6.3V";
"B"
$PN"2"11;
"A"
$PN"1"18;
%"CAP"
"1","(-400,2500)","0","mstr_discrete","I54";
;
CDS_SEC"1"
CDS_LOCATION"C1G5"
SEC"1"
SEC_TYPE"0402"
ROOM"VDDQ_GHJ_PWR_VR"
CDS_LIB"mstr_discrete"
LOCATION"C1G5"
VALUE"0.22UF"
PACK_TYPE"0402"
PART_NUMBER"A36096-155"
TOLERANCE"10%"
VOLTAGE"16V"
MATERIAL"X7R";
"A"
$PN"1"18;
"B"
$PN"2"11;
%"INDUCTOR"
"1","(3100,1950)","0","mstr_discrete","I55";
;
CDS_SEC"1"
SEC_TYPE"SM"
SEC"1"
ROOM"VDDQ_GHJ_PWR_VR"
CDS_LIB"mstr_discrete"
CDS_LOCATION"L1G1"
MATERIAL"IND"
LOCATION"L1G1"
PACK_TYPE"SM"
VALUE"0.12UH"
PART_NUMBER"D92183-034";
"INA\NAC"
$PN"1"29;
"INB\NAC"
$PN"2"1;
%"CAP"
"1","(4000,1750)","0","mstr_discrete","I6";
;
CDS_SEC"1"
SEC_TYPE"0805LF"
SEC"1"
BOM_COST"VDDQ_GHJ_PWR_VR"
ROOM"VDDQ_GHJ_PWR_VR"
CDS_LOCATION"C1G17"
VOLTAGE"4V"
CDS_LIB"mstr_discrete"
LOCATION"C1G17"
PART_NUMBER"C95333-002"
VALUE"22UF"
TOLERANCE"20%"
PACK_TYPE"0805LF"
MATERIAL"X6S";
"A"
$PN"1"1;
"B"
$PN"2"14;
%"PVDDQ_GHJ"
"1","(4000,-325)","0","mstr_symbols","I64";
;
HDL_POWER"PVDDQ_GHJ"
CDS_LIB"mstr_symbols"
BODY_TYPE"PLUMBING"
VOLTAGE"1.2V";
"G\NAC"12;
%"INDUCTOR"
"1","(3100,-425)","0","mstr_discrete","I65";
;
CDS_SEC"1"
CDS_LIB"mstr_discrete"
SEC_TYPE"SM"
SEC"1"
CDS_LOCATION"L1F2"
ROOM"VDDQ_GHJ_PWR_VR"
PACK_TYPE"SM"
MATERIAL"IND"
PART_NUMBER"D92183-034"
VALUE"0.12UH"
LOCATION"L1F2";
"INA\NAC"
$PN"1"21;
"INB\NAC"
$PN"2"12;
%"CAP"
"1","(4000,-625)","0","mstr_discrete","I68";
;
CDS_SEC"1"
SEC_TYPE"0805LF"
SEC"1"
BOM_COST"VDDQ_GHJ_PWR_VR"
ROOM"VDDQ_GHJ_PWR_VR"
CDS_LOCATION"C1G20"
VOLTAGE"4V"
CDS_LIB"mstr_discrete"
LOCATION"C1G20"
PART_NUMBER"C95333-002"
VALUE"22UF"
TOLERANCE"20%"
PACK_TYPE"0805LF"
MATERIAL"X6S";
"A"
$PN"1"12;
"B"
$PN"2"13;
%"GND"
"1","(4000,-850)","0","mstr_symbols","I69";
;
HDL_POWER"GND"
CDS_LIB"mstr_symbols"
VOLTAGE"0"
SIZE"1B"
BODY_TYPE"PLUMBING"
BOM_COST"VDDQ_GHJ_PWR_VR"
ROOM"VDDQ_GHJ_PWR_VR";
"A\NAC"13;
%"GND"
"1","(4000,1525)","0","mstr_symbols","I7";
;
HDL_POWER"GND"
BOM_COST"VDDQ_GHJ_PWR_VR"
VOLTAGE"0"
CDS_LIB"mstr_symbols"
SIZE"1B"
BODY_TYPE"PLUMBING"
ROOM"VDDQ_GHJ_PWR_VR";
"A\NAC"14;
%"GND"
"1","(2325,-875)","0","mstr_symbols","I70";
;
HDL_POWER"GND"
CDS_LIB"mstr_symbols"
SIZE"1B"
VOLTAGE"0"
BODY_TYPE"PLUMBING"
BOM_COST"VDDQ_GHJ_PWR_VR"
ROOM"VDDQ_GHJ_PWR_VR";
"A\NAC"15;
%"CAP"
"1","(-475,150)","0","mstr_discrete","I72";
;
CDS_SEC"1"
CDS_LOCATION"C1G29"
ROOM"VDDQ_GHJ_PWR_VR"
SEC"1"
SEC_TYPE"0402"
CDS_LIB"mstr_discrete"
VALUE"0.22UF"
LOCATION"C1G29"
VOLTAGE"16V"
MATERIAL"X7R"
TOLERANCE"10%"
PART_NUMBER"A36096-155"
PACK_TYPE"0402";
"A"
$PN"1"19;
"B"
$PN"2"17;
%"CAP_A"
"1","(-575,150)","2","dev_discrete","I73";
;
ROOM"VDDQ_GHJ_PWR_VR"
SEC"1"
SEC_TYPE"0402V"
CDS_SEC"1"
CDS_LOCATION"C1F21"
CDS_LIB"dev_discrete"
VOLTAGE"6.3V"
TOLERANCE"10%"
MATERIAL"X6S"
LOCATION"C1F21"
VALUE"1.0UF"
PACK_TYPE"0402V"
PART_NUMBER"D97712-004";
"B"
$PN"2"17;
"A"
$PN"1"19;
%"CAP"
"1","(-975,-475)","2","mstr_discrete","I75";
;
CDS_SEC"1"
CDS_LIB"mstr_discrete"
SPOF"TRUE"
SEC_TYPE"0402"
SEC"1"
CDS_LOCATION"C1F26"
ROOM"VDDQ_GHJ_PWR_VR"
PART_NUMBER"A36096-104"
PACK_TYPE"0402"
TOLERANCE"10%"
MATERIAL"X7R"
LOCATION"C1F26"
VOLTAGE"16V"
VALUE"0.220UF";
"A"
$PN"1"33;
"B"
$PN"2"24;
%"RES"
"1","(-1175,675)","0","mstr_discrete","I76";
;
CDS_SEC"1"
CDS_LOCATION"R9U12"
SEC_TYPE"0402"
SEC"1"
ROOM"VDDQ_GHJ_PWR_VR"
CDS_LIB"mstr_discrete"
PART_NUMBER"G21796-090"
PACK_TYPE"0402"
MATERIAL"CHIP"
LOCATION"R9U12"
TOLERANCE"1%"
VALUE"1.0"
WATTAGE"1/16W";
"B"
$PN"2"19;
"A"
$PN"1"23;
%"CAP"
"1","(-1425,75)","0","mstr_discrete","I77";
;
CDS_SEC"1"
CDS_LOCATION"C1G28"
SEC_TYPE"0402"
SEC"1"
ROOM"VDDQ_GHJ_PWR_VR"
CDS_LIB"mstr_discrete"
VALUE"1.0UF"
LOCATION"C1G28"
TOLERANCE"10%"
VOLTAGE"16V"
MATERIAL"X6S"
PART_NUMBER"D97712-011"
PACK_TYPE"0402";
"A"
$PN"1"23;
"B"
$PN"2"17;
%"CAP_A"
"1","(-1725,125)","0","dev_discrete","I78";
;
CDS_LOCATION"C1F28"
SEC"1"
SEC_TYPE"0402V"
CDS_SEC"1"
ROOM"VDDQ_GHJ_PWR_VR"
CDS_LIB"dev_discrete"
MATERIAL"X7R"
TOLERANCE"10%"
LOCATION"C1F28"
VALUE"0.1UF"
VOLTAGE"16V"
PART_NUMBER"A36096-030"
PACK_TYPE"0402V";
"B"
$PN"2"17;
"A"
$PN"1"16;
%"CAP"
"1","(-1975,100)","0","mstr_discrete","I79";
;
CDS_SEC"1"
SEC"1"
SEC_TYPE"0402"
ROOM"VDDQ_GHJ_PWR_VR"
CDS_LOCATION"C1G13"
CDS_LIB"mstr_discrete"
VALUE"1.0UF"
LOCATION"C1G13"
VOLTAGE"16V"
TOLERANCE"10%"
MATERIAL"X6S"
PART_NUMBER"D97712-011"
PACK_TYPE"0402";
"A"
$PN"1"16;
"B"
$PN"2"17;
%"CAP"
"1","(-2225,100)","0","mstr_discrete","I80";
;
CDS_SEC"1"
SEC"1"
SEC_TYPE"0805"
ROOM"VDDQ_GHJ_PWR_VR"
CDS_LOCATION"C9U3"
CDS_LIB"mstr_discrete"
VOLTAGE"16V"
TOLERANCE"10%"
VALUE"10UF"
LOCATION"C9U3"
MATERIAL"X6S"
PART_NUMBER"C95333-007"
PACK_TYPE"0805";
"A"
$PN"1"16;
"B"
$PN"2"17;
%"CAP"
"1","(-2475,150)","0","mstr_discrete","I81";
;
CDS_SEC"1"
ROOM"VDDQ_GHJ_PWR_VR"
SEC"1"
SEC_TYPE"0805"
CDS_LOCATION"C9T6"
CDS_LIB"mstr_discrete"
LOCATION"C9T6"
TOLERANCE"10%"
VALUE"10UF"
VOLTAGE"16V"
MATERIAL"X6S"
PART_NUMBER"C95333-007"
PACK_TYPE"0805";
"A"
$PN"1"16;
"B"
$PN"2"17;
%"VCC_CORE"
"1","(-2725,600)","0","mstr_symbols","I83";
;
CDS_LIB"mstr_symbols"
HDL_POWER"VR_FET_SW_P12V_STBY_PVDDQ_GHJ";
"A"16;
%"CAP"
"1","(-2725,125)","0","mstr_discrete","I84";
;
CDS_SEC"1"
CDS_LOCATION"C9T9"
SEC"1"
SEC_TYPE"0805"
ROOM"VDDQ_GHJ_PWR_VR"
CDS_LIB"mstr_discrete"
LOCATION"C9T9"
VALUE"10UF"
TOLERANCE"10%"
VOLTAGE"16V"
MATERIAL"X6S"
PART_NUMBER"C95333-007"
PACK_TYPE"0805";
"A"
$PN"1"16;
"B"
$PN"2"17;
%"GND"
"1","(-2725,-250)","0","mstr_symbols","I85";
;
HDL_POWER"GND"
CDS_LIB"mstr_symbols"
VOLTAGE"0"
SIZE"1B"
BODY_TYPE"PLUMBING"
BOM_COST"VDDQ_GHJ_PWR_VR"
ROOM"VDDQ_GHJ_PWR_VR";
"A\NAC"17;
%"P5V_STBY"
"1","(0,3150)","0","mstr_symbols","I87";
;
SIZE"1B"
CDS_LIB"mstr_symbols"
VOLTAGE"5.0V"
BODY_TYPE"PLUMBING"
HDL_POWER"P5V_STBY";
"G\NAC"18;
%"P5V_STBY"
"1","(200,800)","0","mstr_symbols","I88";
;
CDS_LIB"mstr_symbols"
SIZE"1B"
BODY_TYPE"PLUMBING"
VOLTAGE"5.0V"
HDL_POWER"P5V_STBY";
"G\NAC"19;
%"VCC_CORE"
"1","(-2700,2900)","0","mstr_symbols","I89";
;
CDS_LIB"mstr_symbols"
HDL_POWER"VR_FET_SW_P12V_STBY_PVDDQ_GHJ";
"A"20;
END.
